# S9S_MB_2U (Grand Teton) — schematic netlist excerpt (pin names and nets, part order shuffled) for the footprints in the layout excerpt that follows; sources: Cadence DE-HDL packaged netlist, KiCad conversion of 03242023_DA0F0TMBIJ0_F0T_Motherboard_J_brd_V01_OCP.brd

PR3929  Q_RES  1K 1% EMPTY  pkg 0402LF  page 301 : A = HSC_ADDR ; B = HSC_VDD18
PR1785  Q_RES  0 5% CHIP  pkg 0402LF  page 279 : A = PVCCD_HV_CPU0_VOS ; B = PVCCD_HV_CPU0

(kicad_pcb
	(version 20260206)
	(generator "pcbnew")
	(generator_version "10.0")
	(general
		(thickness 1.6)
		(legacy_teardrops no)
	)
	(paper "A4")
	(title_block
		(title "03242023_DA0F0TMBIJ0_F0T_Motherboard_J_brd_V01_OCP.brd")
		(comment 1 "Grand Teton / footprints 5135-5136 of 6105")
	)
	(layers
		(0 "F.Cu" signal "TOP")
		(4 "In1.Cu" signal "GND")
		(6 "In2.Cu" signal "IN1")
		(8 "In3.Cu" signal "GND1")
		(10 "In4.Cu" signal "IN2")
		(12 "In5.Cu" signal "GND2")
		(14 "In6.Cu" signal "IN3")
		(16 "In7.Cu" signal "GND3")
		(18 "In8.Cu" signal "VCC")
		(20 "In9.Cu" signal "VCC1")
		(22 "In10.Cu" signal "GND4")
		(24 "In11.Cu" signal "IN4")
		(26 "In12.Cu" signal "GND5")
		(28 "In13.Cu" signal "IN5")
		(30 "In14.Cu" signal "GND6")
		(32 "In15.Cu" signal "IN6")
		(34 "In16.Cu" signal "GND7")
		(2 "B.Cu" signal "BOTTOM")
		(9 "F.Adhes" user "F.Adhesive")
		(11 "B.Adhes" user "B.Adhesive")
		(13 "F.Paste" user "Package Geometry/Pastemask Top")
		(15 "B.Paste" user "Package Geometry/Pastemask Bottom")
		(5 "F.SilkS" user "Ref Des/Silkscreen Top")
		(7 "B.SilkS" user "Ref Des/Silkscreen Bottom")
		(1 "F.Mask" user "Board Geometry/Soldermask Top")
		(3 "B.Mask" user "Board Geometry/Soldermask Bottom")
		(17 "Dwgs.User" user "User.Drawings")
		(19 "Cmts.User" user "User.Comments")
		(21 "Eco1.User" user "User.Eco1")
		(23 "Eco2.User" user "User.Eco2")
		(25 "Edge.Cuts" user "Board Geometry/Outline")
		(27 "Margin" user)
		(31 "F.CrtYd" user "Package Geometry/Place Bound Top")
		(29 "B.CrtYd" user "Package Geometry/Place Bound Bottom")
		(35 "F.Fab" user "Ref Des/Assembly Top")
		(33 "B.Fab" user "Ref Des/Assembly Bottom")
	)
	(footprint ""
		(layer "B.Cu")
		(at 179.360068 -397.188182)
		(property "Reference" "PR3929"
			(at 0 0 0)
			(layer "B.SilkS")
			(hide yes)
			(effects
				(font
					(size 1.27 1.27)
				)
				(justify mirror)
			)
		)
		(property "Value" ""
			(at 0 0 0)
			(layer "B.Fab")
			(effects
				(font
					(size 1.27 1.27)
				)
				(justify mirror)
			)
		)
		(duplicate_pad_numbers_are_jumpers no)
		(fp_line
			(start -0.7874 -0.4064)
			(end -0.7874 0.4064)
			(stroke
				(width 0.1524)
				(type default)
			)
			(layer "B.SilkS")
		)
		(fp_line
			(start -0.7874 0.4064)
			(end 0.7874 0.4064)
			(stroke
				(width 0.1524)
				(type default)
			)
			(layer "B.SilkS")
		)
		(fp_line
			(start 0.7874 -0.4064)
			(end -0.7874 -0.4064)
			(stroke
				(width 0.1524)
				(type default)
			)
			(layer "B.SilkS")
		)
		(fp_line
			(start 0.7874 0.4064)
			(end 0.7874 -0.4064)
			(stroke
				(width 0.1524)
				(type default)
			)
			(layer "B.SilkS")
		)
		(fp_line
			(start -0.67945 -0.3048)
			(end -0.67945 0.3048)
			(stroke
				(width 0.1)
				(type default)
			)
			(layer "B.Fab")
		)
		(fp_line
			(start -0.67945 0.3048)
			(end -0.120396 0.3048)
			(stroke
				(width 0.1)
				(type default)
			)
			(layer "B.Fab")
		)
		(fp_line
			(start -0.12065 -0.3048)
			(end -0.67945 -0.3048)
			(stroke
				(width 0.1)
				(type default)
			)
			(layer "B.Fab")
		)
		(fp_line
			(start -0.12065 -0.2794)
			(end -0.12065 -0.3048)
			(stroke
				(width 0.1)
				(type default)
			)
			(layer "B.Fab")
		)
		(fp_line
			(start -0.120396 0.2794)
			(end 0.12065 0.2794)
			(stroke
				(width 0.1)
				(type default)
			)
			(layer "B.Fab")
		)
		(fp_line
			(start -0.120396 0.3048)
			(end -0.120396 0.2794)
			(stroke
				(width 0.1)
				(type default)
			)
			(layer "B.Fab")
		)
		(fp_line
			(start 0.12065 -0.305054)
			(end 0.12065 -0.2794)
			(stroke
				(width 0.1)
				(type default)
			)
			(layer "B.Fab")
		)
		(fp_line
			(start 0.12065 -0.2794)
			(end -0.12065 -0.2794)
			(stroke
				(width 0.1)
				(type default)
			)
			(layer "B.Fab")
		)
		(fp_line
			(start 0.12065 0.2794)
			(end 0.12065 0.3048)
			(stroke
				(width 0.1)
				(type default)
			)
			(layer "B.Fab")
		)
		(fp_line
			(start 0.12065 0.3048)
			(end 0.67945 0.3048)
			(stroke
				(width 0.1)
				(type default)
			)
			(layer "B.Fab")
		)
		(fp_line
			(start 0.67945 -0.305054)
			(end 0.12065 -0.305054)
			(stroke
				(width 0.1)
				(type default)
			)
			(layer "B.Fab")
		)
		(fp_line
			(start 0.67945 0.3048)
			(end 0.67945 -0.305054)
			(stroke
				(width 0.1)
				(type default)
			)
			(layer "B.Fab")
		)
		(pad "1" smd circle
			(at 0.40005 0 180)
			(size 0 0)
			(layers "B.Cu" "B.Mask" "B.Paste")
			(net "HSC_ADDR")
		)
		(pad "2" smd circle
			(at -0.40005 0 180)
			(size 0 0)
			(layers "B.Cu" "B.Mask" "B.Paste")
			(net "HSC_VDD18")
		)
	)
	(footprint ""
		(layer "B.Cu")
		(at 418.540692 -166.050214 180)
		(property "Reference" "PR1785"
			(at 0 0 0)
			(layer "B.SilkS")
			(hide yes)
			(effects
				(font
					(size 1.27 1.27)
				)
				(justify mirror)
			)
		)
		(property "Value" ""
			(at 0 0 0)
			(layer "B.Fab")
			(effects
				(font
					(size 1.27 1.27)
				)
				(justify mirror)
			)
		)
		(duplicate_pad_numbers_are_jumpers no)
		(fp_line
			(start 0.7874 0.4064)
			(end 0.7874 -0.4064)
			(stroke
				(width 0.1524)
				(type default)
			)
			(layer "B.SilkS")
		)
		(fp_line
			(start 0.7874 -0.4064)
			(end -0.7874 -0.4064)
			(stroke
				(width 0.1524)
				(type default)
			)
			(layer "B.SilkS")
		)
		(fp_line
			(start -0.7874 0.4064)
			(end 0.7874 0.4064)
			(stroke
				(width 0.1524)
				(type default)
			)
			(layer "B.SilkS")
		)
		(fp_line
			(start -0.7874 -0.4064)
			(end -0.7874 0.4064)
			(stroke
				(width 0.1524)
				(type default)
			)
			(layer "B.SilkS")
		)
		(fp_line
			(start 0.67945 0.3048)
			(end 0.67945 -0.305054)
			(stroke
				(width 0.1)
				(type default)
			)
			(layer "B.Fab")
		)
		(fp_line
			(start 0.67945 -0.305054)
			(end 0.12065 -0.305054)
			(stroke
				(width 0.1)
				(type default)
			)
			(layer "B.Fab")
		)
		(fp_line
			(start 0.12065 0.3048)
			(end 0.67945 0.3048)
			(stroke
				(width 0.1)
				(type default)
			)
			(layer "B.Fab")
		)
		(fp_line
			(start 0.12065 0.2794)
			(end 0.12065 0.3048)
			(stroke
				(width 0.1)
				(type default)
			)
			(layer "B.Fab")
		)
		(fp_line
			(start 0.12065 -0.2794)
			(end -0.12065 -0.2794)
			(stroke
				(width 0.1)
				(type default)
			)
			(layer "B.Fab")
		)
		(fp_line
			(start 0.12065 -0.305054)
			(end 0.12065 -0.2794)
			(stroke
				(width 0.1)
				(type default)
			)
			(layer "B.Fab")
		)
		(fp_line
			(start -0.120396 0.3048)
			(end -0.120396 0.2794)
			(stroke
				(width 0.1)
				(type default)
			)
			(layer "B.Fab")
		)
		(fp_line
			(start -0.120396 0.2794)
			(end 0.12065 0.2794)
			(stroke
				(width 0.1)
				(type default)
			)
			(layer "B.Fab")
		)
		(fp_line
			(start -0.12065 -0.2794)
			(end -0.12065 -0.3048)
			(stroke
				(width 0.1)
				(type default)
			)
			(layer "B.Fab")
		)
		(fp_line
			(start -0.12065 -0.3048)
			(end -0.67945 -0.3048)
			(stroke
				(width 0.1)
				(type default)
			)
			(layer "B.Fab")
		)
		(fp_line
			(start -0.67945 0.3048)
			(end -0.120396 0.3048)
			(stroke
				(width 0.1)
				(type default)
			)
			(layer "B.Fab")
		)
		(fp_line
			(start -0.67945 -0.3048)
			(end -0.67945 0.3048)
			(stroke
				(width 0.1)
				(type default)
			)
			(layer "B.Fab")
		)
		(pad "1" smd circle
			(at 0.40005 0)
			(size 0 0)
			(layers "B.Cu" "B.Mask" "B.Paste")
			(net "PVCCD_HV_CPU0_VOS")
		)
		(pad "2" smd circle
			(at -0.40005 0)
			(size 0 0)
			(layers "B.Cu" "B.Mask" "B.Paste")
			(net "PVCCD_HV_CPU0")
		)
	)
)
